# S9S_MB_2U (Grand Teton) — schematic netlist excerpt (pin names and nets, part order shuffled) for the footprints in the layout excerpt that follows; sources: Cadence DE-HDL packaged netlist, KiCad conversion of 03242023_DA0F0TMBIJ0_F0T_Motherboard_J_brd_V01_OCP.brd

R4159  Q_RES  100K 1% EMPTY  pkg 0402LF  page 145 : A = GPU_3V3IO_RSVD1 ; B = GND
R2322  Q_RES  49.9 1% EMPTY  pkg 0402LF  page 274 : A = PVNN_TERM_CPU0 ; B = SVID_CLK0_CPU0_R

(kicad_pcb
	(version 20260206)
	(generator "pcbnew")
	(generator_version "10.0")
	(general
		(thickness 1.6)
		(legacy_teardrops no)
	)
	(paper "A4")
	(title_block
		(title "03242023_DA0F0TMBIJ0_F0T_Motherboard_J_brd_V01_OCP.brd")
		(comment 1 "Grand Teton / footprints 1621-1622 of 6105")
	)
	(layers
		(0 "F.Cu" signal "TOP")
		(4 "In1.Cu" signal "GND")
		(6 "In2.Cu" signal "IN1")
		(8 "In3.Cu" signal "GND1")
		(10 "In4.Cu" signal "IN2")
		(12 "In5.Cu" signal "GND2")
		(14 "In6.Cu" signal "IN3")
		(16 "In7.Cu" signal "GND3")
		(18 "In8.Cu" signal "VCC")
		(20 "In9.Cu" signal "VCC1")
		(22 "In10.Cu" signal "GND4")
		(24 "In11.Cu" signal "IN4")
		(26 "In12.Cu" signal "GND5")
		(28 "In13.Cu" signal "IN5")
		(30 "In14.Cu" signal "GND6")
		(32 "In15.Cu" signal "IN6")
		(34 "In16.Cu" signal "GND7")
		(2 "B.Cu" signal "BOTTOM")
		(9 "F.Adhes" user "F.Adhesive")
		(11 "B.Adhes" user "B.Adhesive")
		(13 "F.Paste" user "Package Geometry/Pastemask Top")
		(15 "B.Paste" user "Package Geometry/Pastemask Bottom")
		(5 "F.SilkS" user "Ref Des/Silkscreen Top")
		(7 "B.SilkS" user "Ref Des/Silkscreen Bottom")
		(1 "F.Mask" user "Board Geometry/Soldermask Top")
		(3 "B.Mask" user "Board Geometry/Soldermask Bottom")
		(17 "Dwgs.User" user "User.Drawings")
		(19 "Cmts.User" user "User.Comments")
		(21 "Eco1.User" user "User.Eco1")
		(23 "Eco2.User" user "User.Eco2")
		(25 "Edge.Cuts" user "Board Geometry/Outline")
		(27 "Margin" user)
		(31 "F.CrtYd" user "Package Geometry/Place Bound Top")
		(29 "B.CrtYd" user "Package Geometry/Place Bound Bottom")
		(35 "F.Fab" user "Ref Des/Assembly Top")
		(33 "B.Fab" user "Ref Des/Assembly Bottom")
	)
	(footprint ""
		(layer "F.Cu")
		(at 357.487982 -386.41909 180)
		(property "Reference" "R4159"
			(at 0 0 180)
			(layer "F.SilkS")
			(hide yes)
			(effects
				(font
					(size 1.27 1.27)
				)
			)
		)
		(property "Value" ""
			(at 0 0 180)
			(layer "F.Fab")
			(effects
				(font
					(size 1.27 1.27)
				)
			)
		)
		(duplicate_pad_numbers_are_jumpers no)
		(fp_line
			(start 0.7874 0.4064)
			(end -0.7874 0.4064)
			(stroke
				(width 0.1524)
				(type default)
			)
			(layer "F.SilkS")
		)
		(fp_line
			(start 0.7874 -0.4064)
			(end 0.7874 0.4064)
			(stroke
				(width 0.1524)
				(type default)
			)
			(layer "F.SilkS")
		)
		(fp_line
			(start -0.7874 0.4064)
			(end -0.7874 -0.4064)
			(stroke
				(width 0.1524)
				(type default)
			)
			(layer "F.SilkS")
		)
		(fp_line
			(start -0.7874 -0.4064)
			(end 0.7874 -0.4064)
			(stroke
				(width 0.1524)
				(type default)
			)
			(layer "F.SilkS")
		)
		(fp_line
			(start 0.67945 0.3048)
			(end 0.120396 0.3048)
			(stroke
				(width 0.1)
				(type default)
			)
			(layer "F.Fab")
		)
		(fp_line
			(start 0.67945 -0.3048)
			(end 0.67945 0.3048)
			(stroke
				(width 0.1)
				(type default)
			)
			(layer "F.Fab")
		)
		(fp_line
			(start 0.12065 -0.2794)
			(end 0.12065 -0.3048)
			(stroke
				(width 0.1)
				(type default)
			)
			(layer "F.Fab")
		)
		(fp_line
			(start 0.12065 -0.3048)
			(end 0.67945 -0.3048)
			(stroke
				(width 0.1)
				(type default)
			)
			(layer "F.Fab")
		)
		(fp_line
			(start 0.120396 0.3048)
			(end 0.120396 0.2794)
			(stroke
				(width 0.1)
				(type default)
			)
			(layer "F.Fab")
		)
		(fp_line
			(start 0.120396 0.2794)
			(end -0.12065 0.2794)
			(stroke
				(width 0.1)
				(type default)
			)
			(layer "F.Fab")
		)
		(fp_line
			(start -0.12065 0.3048)
			(end -0.67945 0.3048)
			(stroke
				(width 0.1)
				(type default)
			)
			(layer "F.Fab")
		)
		(fp_line
			(start -0.12065 0.2794)
			(end -0.12065 0.3048)
			(stroke
				(width 0.1)
				(type default)
			)
			(layer "F.Fab")
		)
		(fp_line
			(start -0.12065 -0.2794)
			(end 0.12065 -0.2794)
			(stroke
				(width 0.1)
				(type default)
			)
			(layer "F.Fab")
		)
		(fp_line
			(start -0.12065 -0.305054)
			(end -0.12065 -0.2794)
			(stroke
				(width 0.1)
				(type default)
			)
			(layer "F.Fab")
		)
		(fp_line
			(start -0.67945 0.3048)
			(end -0.67945 -0.305054)
			(stroke
				(width 0.1)
				(type default)
			)
			(layer "F.Fab")
		)
		(fp_line
			(start -0.67945 -0.305054)
			(end -0.12065 -0.305054)
			(stroke
				(width 0.1)
				(type default)
			)
			(layer "F.Fab")
		)
		(pad "1" smd circle
			(at -0.40005 0 180)
			(size 0 0)
			(layers "F.Cu" "F.Mask" "F.Paste")
			(net "GPU_3V3IO_RSVD1")
		)
		(pad "2" smd circle
			(at 0.40005 0 180)
			(size 0 0)
			(layers "F.Cu" "F.Mask" "F.Paste")
			(net "GND")
		)
	)
	(footprint ""
		(layer "F.Cu")
		(at 432.38928 -136.644888 90)
		(property "Reference" "R2322"
			(at 0 0 90)
			(layer "F.SilkS")
			(hide yes)
			(effects
				(font
					(size 1.27 1.27)
				)
			)
		)
		(property "Value" ""
			(at 0 0 90)
			(layer "F.Fab")
			(effects
				(font
					(size 1.27 1.27)
				)
			)
		)
		(duplicate_pad_numbers_are_jumpers no)
		(fp_line
			(start 0.7874 -0.4064)
			(end 0.7874 0.4064)
			(stroke
				(width 0.1524)
				(type default)
			)
			(layer "F.SilkS")
		)
		(fp_line
			(start -0.7874 -0.4064)
			(end 0.7874 -0.4064)
			(stroke
				(width 0.1524)
				(type default)
			)
			(layer "F.SilkS")
		)
		(fp_line
			(start 0.7874 0.4064)
			(end -0.7874 0.4064)
			(stroke
				(width 0.1524)
				(type default)
			)
			(layer "F.SilkS")
		)
		(fp_line
			(start -0.7874 0.4064)
			(end -0.7874 -0.4064)
			(stroke
				(width 0.1524)
				(type default)
			)
			(layer "F.SilkS")
		)
		(fp_line
			(start -0.12065 -0.305054)
			(end -0.12065 -0.2794)
			(stroke
				(width 0.1)
				(type default)
			)
			(layer "F.Fab")
		)
		(fp_line
			(start -0.67945 -0.305054)
			(end -0.12065 -0.305054)
			(stroke
				(width 0.1)
				(type default)
			)
			(layer "F.Fab")
		)
		(fp_line
			(start 0.67945 -0.3048)
			(end 0.67945 0.3048)
			(stroke
				(width 0.1)
				(type default)
			)
			(layer "F.Fab")
		)
		(fp_line
			(start 0.12065 -0.3048)
			(end 0.67945 -0.3048)
			(stroke
				(width 0.1)
				(type default)
			)
			(layer "F.Fab")
		)
		(fp_line
			(start 0.12065 -0.2794)
			(end 0.12065 -0.3048)
			(stroke
				(width 0.1)
				(type default)
			)
			(layer "F.Fab")
		)
		(fp_line
			(start -0.12065 -0.2794)
			(end 0.12065 -0.2794)
			(stroke
				(width 0.1)
				(type default)
			)
			(layer "F.Fab")
		)
		(fp_line
			(start 0.120396 0.2794)
			(end -0.12065 0.2794)
			(stroke
				(width 0.1)
				(type default)
			)
			(layer "F.Fab")
		)
		(fp_line
			(start -0.12065 0.2794)
			(end -0.12065 0.3048)
			(stroke
				(width 0.1)
				(type default)
			)
			(layer "F.Fab")
		)
		(fp_line
			(start 0.67945 0.3048)
			(end 0.120396 0.3048)
			(stroke
				(width 0.1)
				(type default)
			)
			(layer "F.Fab")
		)
		(fp_line
			(start 0.120396 0.3048)
			(end 0.120396 0.2794)
			(stroke
				(width 0.1)
				(type default)
			)
			(layer "F.Fab")
		)
		(fp_line
			(start -0.12065 0.3048)
			(end -0.67945 0.3048)
			(stroke
				(width 0.1)
				(type default)
			)
			(layer "F.Fab")
		)
		(fp_line
			(start -0.67945 0.3048)
			(end -0.67945 -0.305054)
			(stroke
				(width 0.1)
				(type default)
			)
			(layer "F.Fab")
		)
		(pad "1" smd circle
			(at -0.40005 0 90)
			(size 0 0)
			(layers "F.Cu" "F.Mask" "F.Paste")
			(net "PVNN_TERM_CPU0")
		)
		(pad "2" smd circle
			(at 0.40005 0 90)
			(size 0 0)
			(layers "F.Cu" "F.Mask" "F.Paste")
			(net "SVID_CLK0_CPU0_R")
		)
	)
)
